# BASEBOARD_FAB2 (Tioga Pass) — schematic netlist excerpt (pin names and nets, part order shuffled) for the footprints in the layout excerpt that follows; sources: Cadence DE-HDL packaged netlist, KiCad conversion of Wiwynn_Tioga_Pass_MB.brd

J9L1  SCONN288_H44441003  SCONN  pkg PIP  page 88
  \12v\(1)  = P12V_NVDIMM_KLM
  VSS(93)  = GND
  DQ(4)  = M_M_DQ<4>
  VSS(92)  = GND
  DQ(0)  = M_M_DQ<0>
  VSS(91)  = GND
  DQS9P  = M_M_DQS_DP<9>
  DQS9N  = M_M_DQS_DN<9>
  VSS(90)  = GND
  DQ(6)  = M_M_DQ<6>
  VSS(89)  = GND
  DQ(2)  = M_M_DQ<2>
  VSS(88)  = GND
  DQ(12)  = M_M_DQ<12>
  VSS(87)  = GND
  DQ(8)  = M_M_DQ<8>
  VSS(86)  = GND
  DQS10P  = M_M_DQS_DP<10>
  DQS10N  = M_M_DQS_DN<10>
  VSS(85)  = GND
  DQ(14)  = M_M_DQ<14>
  VSS(84)  = GND
  DQ(10)  = M_M_DQ<10>
  VSS(83)  = GND
  DQ(20)  = M_M_DQ<20>
  VSS(82)  = GND
  DQ(16)  = M_M_DQ<16>
  VSS(81)  = GND
  DQS11P  = M_M_DQS_DP<11>
  DQS11N  = M_M_DQS_DN<11>
  VSS(80)  = GND
  DQ(22)  = M_M_DQ<22>
  VSS(79)  = GND
  DQ(18)  = M_M_DQ<18>
  VSS(78)  = GND
  DQ(28)  = M_M_DQ<28>
  VSS(77)  = GND
  DQ(24)  = M_M_DQ<24>
  VSS(76)  = GND
  DQS12P  = M_M_DQS_DP<12>
  DQS12N  = M_M_DQS_DN<12>
  VSS(75)  = GND
  DQ(30)  = M_M_DQ<30>
  VSS(74)  = GND
  DQ(26)  = M_M_DQ<26>
  VSS(73)  = GND
  CB(4)  = M_M_ECC<4>
  VSS(72)  = GND
  CB(0)  = M_M_ECC<0>
  VSS(71)  = GND
  DQS17P  = M_M_DQS_DP<17>
  DQS17N  = M_M_DQS_DN<17>
  VSS(70)  = GND
  CB(6)  = M_M_ECC<6>
  VSS(69)  = GND
  CB(2)  = M_M_ECC<2>
  VSS(68)  = GND
  RESET_N  = M_KLM_RST_N
  VDD(25)  = PVDDQ_KLM
  CKE(0)  = M_M_CKE<2>
  VDD(24)  = PVDDQ_KLM
  ACT_N  = M_M_ACT_N
  BG(0)  = M_M_BG<0>
  VDD(23)  = PVDDQ_KLM
  A12  = M_M_MA<12>
  A9  = M_M_MA<9>
  VDD(22)  = PVDDQ_KLM
  A8  = M_M_MA<8>
  A6  = M_M_MA<6>
  VDD(21)  = PVDDQ_KLM
  A3  = M_M_MA<3>
  A1  = M_M_MA<1>
  VDD(20)  = PVDDQ_KLM
  CK0P  = M_M_CLK_DP<2>
  CK0N  = M_M_CLK_DN<2>
  VDD(19)  = PVDDQ_KLM
  VTT(1)  = PVTT_KLM
  EVENT_N  = FM_DIMM_EVENT_COD_N
  A0  = M_M_MA<0>
  VDD(18)  = PVDDQ_KLM
  BA(0)  = M_M_BA<0>
  A16_RAS_N  = M_M_MA<16>
  VDD(17)  = PVDDQ_KLM
  S0_N  = M_M_CS_N<4>
  VDD(16)  = PVDDQ_KLM
  A15_CAS_N  = M_M_MA<15>
  ODT(0)  = M_M_ODT<2>
  VDD(15)  = PVDDQ_KLM
  S1_N  = M_M_CS_N<5>
  VDD(14)  = PVDDQ_KLM
  ODT(1)  = M_M_ODT<3>
  VDD(13)  = PVDDQ_KLM
  S2_N_C(0)  = M_M_CS_N<6>
  VSS(67)  = GND
  DQ(36)  = M_M_DQ<36>
  VSS(66)  = GND
  DQ(32)  = M_M_DQ<32>
  VSS(65)  = GND
  DQS13P  = M_M_DQS_DP<13>
  DQS13N  = M_M_DQS_DN<13>
  VSS(64)  = GND
  DQ(38)  = M_M_DQ<38>
  VSS(63)  = GND
  DQ(34)  = M_M_DQ<34>
  VSS(62)  = GND
  DQ(44)  = M_M_DQ<44>
  VSS(61)  = GND
  DQ(40)  = M_M_DQ<40>
  VSS(60)  = GND
  DQS14P  = M_M_DQS_DP<14>
  DQS14N  = M_M_DQS_DN<14>
  VSS(59)  = GND
  DQ(46)  = M_M_DQ<46>
  VSS(58)  = GND
  DQ(42)  = M_M_DQ<42>
  VSS(57)  = GND
  DQ(52)  = M_M_DQ<52>
  VSS(56)  = GND
  DQ(48)  = M_M_DQ<48>
  VSS(55)  = GND
  DQS15P  = M_M_DQS_DP<15>
  DQS15N  = M_M_DQS_DN<15>
  VSS(54)  = GND
  DQ(54)  = M_M_DQ<54>
  VSS(53)  = GND
  DQ(50)  = M_M_DQ<50>
  VSS(52)  = GND
  DQ(60)  = M_M_DQ<60>
  VSS(51)  = GND
  DQ(56)  = M_M_DQ<56>
  VSS(50)  = GND
  DQS16P  = M_M_DQS_DP<16>
  DQS16N  = M_M_DQS_DN<16>
  VSS(49)  = GND
  DQ(62)  = M_M_DQ<62>
  VSS(48)  = GND
  DQ(58)  = M_M_DQ<58>
  VSS(47)  = GND
  SA(0)  = PVPP_KLM
  SA(1)  = GND
  SCL  = SMB_DDR_KLM_VPP_SCL
  VPP(4)  = PVPP_KLM
  VPP(3)  = PVPP_KLM
  RFU(2)  = TP_CH_M_DIMM_M1_RFU_2
  \12v\(0)  = P12V_NVDIMM_KLM
  VREFCA  = M_M_VREF
  VSS(46)  = GND
  DQ(5)  = M_M_DQ<5>
  VSS(45)  = GND
  DQ(1)  = M_M_DQ<1>
  VSS(44)  = GND
  DQS0N  = M_M_DQS_DN<0>
  DQS0P  = M_M_DQS_DP<0>
  VSS(43)  = GND
  DQ(7)  = M_M_DQ<7>
  VSS(42)  = GND
  DQ(3)  = M_M_DQ<3>
  VSS(41)  = GND
  DQ(13)  = M_M_DQ<13>
  VSS(40)  = GND
  DQ(9)  = M_M_DQ<9>
  VSS(39)  = GND
  DQS1N  = M_M_DQS_DN<1>
  DQS1P  = M_M_DQS_DP<1>
  VSS(38)  = GND
  DQ(15)  = M_M_DQ<15>
  VSS(37)  = GND
  DQ(11)  = M_M_DQ<11>
  VSS(36)  = GND
  DQ(21)  = M_M_DQ<21>
  VSS(35)  = GND
  DQ(17)  = M_M_DQ<17>
  VSS(34)  = GND
  DQS2N  = M_M_DQS_DN<2>
  DQS2P  = M_M_DQS_DP<2>
  VSS(33)  = GND
  DQ(23)  = M_M_DQ<23>
  VSS(32)  = GND
  DQ(19)  = M_M_DQ<19>
  VSS(31)  = GND
  DQ(29)  = M_M_DQ<29>
  VSS(30)  = GND
  DQ(25)  = M_M_DQ<25>
  VSS(29)  = GND
  DQS3N  = M_M_DQS_DN<3>
  DQS3P  = M_M_DQS_DP<3>
  VSS(28)  = GND
  DQ(31)  = M_M_DQ<31>
  VSS(27)  = GND
  DQ(27)  = M_M_DQ<27>
  VSS(26)  = GND
  CB(5)  = M_M_ECC<5>
  VSS(25)  = GND
  CB(1)  = M_M_ECC<1>
  VSS(24)  = GND
  DQS8N  = M_M_DQS_DN<8>
  DQS8P  = M_M_DQS_DP<8>
  VSS(23)  = GND
  CB(7)  = M_M_ECC<7>
  VSS(22)  = GND
  CB(3)  = M_M_ECC<3>
  VSS(21)  = GND
  CKE(1)  = M_M_CKE<3>
  VDD(12)  = PVDDQ_KLM
  RFU(0)  = TP_CH_M_DIMM_M1_RFU_0
  VDD(11)  = PVDDQ_KLM
  BG(1)  = M_M_BG<1>
  ALERT_N  = M_M_ALERT_N
  VDD(10)  = PVDDQ_KLM
  A11  = M_M_MA<11>
  A7  = M_M_MA<7>
  VDD(9)  = PVDDQ_KLM
  A5  = M_M_MA<5>
  A4  = M_M_MA<4>
  VDD(8)  = PVDDQ_KLM
  A2  = M_M_MA<2>
  VDD(7)  = PVDDQ_KLM
  CK1P  = M_M_CLK_DP<3>
  CK1N  = M_M_CLK_DN<3>
  VDD(6)  = PVDDQ_KLM
  VTT(0)  = PVTT_KLM
  PAR  = M_M_PAR
  VDD(5)  = PVDDQ_KLM
  BA(1)  = M_M_BA<1>
  A10  = M_M_MA<10>
  VDD(4)  = PVDDQ_KLM
  RFU(1)  = TP_CH_M_DIMM_M1_RFU_1
  A14_WE_N  = M_M_MA<14>
  VDD(3)  = PVDDQ_KLM
  SAVE_N_NC  = FM_ADR_COMPLETE_KLM_N
  VDD(2)  = PVDDQ_KLM
  A13  = M_M_MA<13>
  VDD(1)  = PVDDQ_KLM
  A17  = M_M_MA<17>
  C(2)  = M_M_C<2>
  VDD(0)  = PVDDQ_KLM
  S3_N_C(1)  = M_M_CS_N<7>
  SA(2)  = PVPP_KLM
  VSS(20)  = GND
  DQ(37)  = M_M_DQ<37>
  VSS(19)  = GND
  DQ(33)  = M_M_DQ<33>
  VSS(18)  = GND
  DQS4N  = M_M_DQS_DN<4>
  DQS4P  = M_M_DQS_DP<4>
  VSS(17)  = GND
  DQ(39)  = M_M_DQ<39>
  VSS(16)  = GND
  DQ(35)  = M_M_DQ<35>
  VSS(15)  = GND
  DQ(45)  = M_M_DQ<45>
  VSS(14)  = GND
  DQ(41)  = M_M_DQ<41>
  VSS(13)  = GND
  DQS5N  = M_M_DQS_DN<5>
  DQS5P  = M_M_DQS_DP<5>
  VSS(12)  = GND
  DQ(47)  = M_M_DQ<47>
  VSS(11)  = GND
  DQ(43)  = M_M_DQ<43>
  VSS(10)  = GND
  DQ(53)  = M_M_DQ<53>
  VSS(9)  = GND
  DQ(49)  = M_M_DQ<49>
  VSS(8)  = GND
  DQS6N  = M_M_DQS_DN<6>
  DQS6P  = M_M_DQS_DP<6>
  VSS(7)  = GND
  DQ(55)  = M_M_DQ<55>
  VSS(6)  = GND
  DQ(51)  = M_M_DQ<51>
  VSS(5)  = GND
  DQ(61)  = M_M_DQ<61>
  VSS(4)  = GND
  DQ(57)  = M_M_DQ<57>
  VSS(3)  = GND
  DQS7N  = M_M_DQS_DN<7>
  DQS7P  = M_M_DQS_DP<7>
  VSS(2)  = GND
  DQ(63)  = M_M_DQ<63>
  VSS(1)  = GND
  DQ(59)  = M_M_DQ<59>
  VSS(0)  = GND
  VDDSPD  = PVPP_KLM
  SDA  = SMB_DDR_KLM_VPP_SDA
  VPP(1)  = PVPP_KLM
  VPP(0)  = PVPP_KLM
  VPP(2)  = PVPP_KLM

(kicad_pcb
	(version 20260206)
	(generator "pcbnew")
	(generator_version "10.0")
	(general
		(thickness 1.6)
		(legacy_teardrops no)
	)
	(paper "A4")
	(title_block
		(title "Wiwynn_Tioga_Pass_MB.brd")
		(comment 1 "Tioga Pass / footprint 2717 of 4770 (J9L1), pads 250-291 of 291")
	)
	(layers
		(0 "F.Cu" signal "TOP")
		(4 "In1.Cu" signal "L2GND")
		(6 "In2.Cu" signal "L3")
		(8 "In3.Cu" signal "L4GND")
		(10 "In4.Cu" signal "L5")
		(12 "In5.Cu" signal "L6GND")
		(14 "In6.Cu" signal "L7VCC")
		(16 "In7.Cu" signal "L8VCC")
		(18 "In8.Cu" signal "L9GND")
		(20 "In9.Cu" signal "L10")
		(22 "In10.Cu" signal "L11GND")
		(24 "In11.Cu" signal "L12")
		(26 "In12.Cu" signal "L13GND")
		(2 "B.Cu" signal "BOTTOM")
		(9 "F.Adhes" user "F.Adhesive")
		(11 "B.Adhes" user "B.Adhesive")
		(13 "F.Paste" user "Package Geometry/Pastemask Top")
		(15 "B.Paste" user "Package Geometry/Pastemask Bottom")
		(5 "F.SilkS" user "Ref Des/Silkscreen Top")
		(7 "B.SilkS" user "Ref Des/Silkscreen Bottom")
		(1 "F.Mask" user "Board Geometry/Soldermask Top")
		(3 "B.Mask" user "Board Geometry/Soldermask Bottom")
		(17 "Dwgs.User" user "User.Drawings")
		(19 "Cmts.User" user "User.Comments")
		(21 "Eco1.User" user "User.Eco1")
		(23 "Eco2.User" user "User.Eco2")
		(25 "Edge.Cuts" user "Board Geometry/Outline")
		(27 "Margin" user)
		(31 "F.CrtYd" user "Package Geometry/Place Bound Top")
		(29 "B.CrtYd" user "Package Geometry/Place Bound Bottom")
		(35 "F.Fab" user "Ref Des/Assembly Top")
		(33 "B.Fab" user "Ref Des/Assembly Bottom")
	)
	(footprint ""
		(layer "B.Cu")
		(at 29.699458 -152.078436 90)
		(property "Reference" "J9L1"
			(at 2.200148 37.737542 0)
			(unlocked yes)
			(layer "B.SilkS")
			(effects
				(font
					(size 0.7874 0.5842)
					(thickness 0.1524)
				)
				(justify left mirror)
			)
		)
		(property "Value" ""
			(at 0 0 90)
			(layer "B.Fab")
			(effects
				(font
					(size 1.27 1.27)
				)
				(justify mirror)
			)
		)
		(duplicate_pad_numbers_are_jumpers no)
		(pad "247" smd rect
			(at -4.59994 91.799918 270)
			(size 1.8034 0.508)
			(layers "B.Cu" "B.Mask" "B.Paste")
			(net "M_M_DQ<39>")
		)
		(pad "248" smd rect
			(at -4.59994 92.650056 270)
			(size 1.8034 0.508)
			(layers "B.Cu" "B.Mask" "B.Paste")
			(net "GND")
		)
		(pad "249" smd rect
			(at -4.59994 93.49994 270)
			(size 1.8034 0.508)
			(layers "B.Cu" "B.Mask" "B.Paste")
			(net "M_M_DQ<35>")
		)
		(pad "250" smd rect
			(at -4.59994 94.350078 270)
			(size 1.8034 0.508)
			(layers "B.Cu" "B.Mask" "B.Paste")
			(net "GND")
		)
		(pad "251" smd rect
			(at -4.59994 95.199962 270)
			(size 1.8034 0.508)
			(layers "B.Cu" "B.Mask" "B.Paste")
			(net "M_M_DQ<45>")
		)
		(pad "252" smd rect
			(at -4.59994 96.0501 270)
			(size 1.8034 0.508)
			(layers "B.Cu" "B.Mask" "B.Paste")
			(net "GND")
		)
		(pad "253" smd rect
			(at -4.59994 96.899984 270)
			(size 1.8034 0.508)
			(layers "B.Cu" "B.Mask" "B.Paste")
			(net "M_M_DQ<41>")
		)
		(pad "254" smd rect
			(at -4.59994 97.750122 270)
			(size 1.8034 0.508)
			(layers "B.Cu" "B.Mask" "B.Paste")
			(net "GND")
		)
		(pad "255" smd rect
			(at -4.59994 98.600006 270)
			(size 1.8034 0.508)
			(layers "B.Cu" "B.Mask" "B.Paste")
			(net "M_M_DQS_DN<5>")
		)
		(pad "256" smd rect
			(at -4.59994 99.44989 270)
			(size 1.8034 0.508)
			(layers "B.Cu" "B.Mask" "B.Paste")
			(net "M_M_DQS_DP<5>")
		)
		(pad "257" smd rect
			(at -4.59994 100.300028 270)
			(size 1.8034 0.508)
			(layers "B.Cu" "B.Mask" "B.Paste")
			(net "GND")
		)
		(pad "258" smd rect
			(at -4.59994 101.149912 270)
			(size 1.8034 0.508)
			(layers "B.Cu" "B.Mask" "B.Paste")
			(net "M_M_DQ<47>")
		)
		(pad "259" smd rect
			(at -4.59994 102.00005 270)
			(size 1.8034 0.508)
			(layers "B.Cu" "B.Mask" "B.Paste")
			(net "GND")
		)
		(pad "260" smd rect
			(at -4.59994 102.849934 270)
			(size 1.8034 0.508)
			(layers "B.Cu" "B.Mask" "B.Paste")
			(net "M_M_DQ<43>")
		)
		(pad "261" smd rect
			(at -4.59994 103.700072 270)
			(size 1.8034 0.508)
			(layers "B.Cu" "B.Mask" "B.Paste")
			(net "GND")
		)
		(pad "262" smd rect
			(at -4.59994 104.549956 270)
			(size 1.8034 0.508)
			(layers "B.Cu" "B.Mask" "B.Paste")
			(net "M_M_DQ<53>")
		)
		(pad "263" smd rect
			(at -4.59994 105.400094 270)
			(size 1.8034 0.508)
			(layers "B.Cu" "B.Mask" "B.Paste")
			(net "GND")
		)
		(pad "264" smd rect
			(at -4.59994 106.249978 270)
			(size 1.8034 0.508)
			(layers "B.Cu" "B.Mask" "B.Paste")
			(net "M_M_DQ<49>")
		)
		(pad "265" smd rect
			(at -4.59994 107.100116 270)
			(size 1.8034 0.508)
			(layers "B.Cu" "B.Mask" "B.Paste")
			(net "GND")
		)
		(pad "266" smd rect
			(at -4.59994 107.95 270)
			(size 1.8034 0.508)
			(layers "B.Cu" "B.Mask" "B.Paste")
			(net "M_M_DQS_DN<6>")
		)
		(pad "267" smd rect
			(at -4.59994 108.799884 270)
			(size 1.8034 0.508)
			(layers "B.Cu" "B.Mask" "B.Paste")
			(net "M_M_DQS_DP<6>")
		)
		(pad "268" smd rect
			(at -4.59994 109.650022 270)
			(size 1.8034 0.508)
			(layers "B.Cu" "B.Mask" "B.Paste")
			(net "GND")
		)
		(pad "269" smd rect
			(at -4.59994 110.499906 270)
			(size 1.8034 0.508)
			(layers "B.Cu" "B.Mask" "B.Paste")
			(net "M_M_DQ<55>")
		)
		(pad "270" smd rect
			(at -4.59994 111.350044 270)
			(size 1.8034 0.508)
			(layers "B.Cu" "B.Mask" "B.Paste")
			(net "GND")
		)
		(pad "271" smd rect
			(at -4.59994 112.199928 270)
			(size 1.8034 0.508)
			(layers "B.Cu" "B.Mask" "B.Paste")
			(net "M_M_DQ<51>")
		)
		(pad "272" smd rect
			(at -4.59994 113.050066 270)
			(size 1.8034 0.508)
			(layers "B.Cu" "B.Mask" "B.Paste")
			(net "GND")
		)
		(pad "273" smd rect
			(at -4.59994 113.89995 270)
			(size 1.8034 0.508)
			(layers "B.Cu" "B.Mask" "B.Paste")
			(net "M_M_DQ<61>")
		)
		(pad "274" smd rect
			(at -4.59994 114.750088 270)
			(size 1.8034 0.508)
			(layers "B.Cu" "B.Mask" "B.Paste")
			(net "GND")
		)
		(pad "275" smd rect
			(at -4.59994 115.599972 270)
			(size 1.8034 0.508)
			(layers "B.Cu" "B.Mask" "B.Paste")
			(net "M_M_DQ<57>")
		)
		(pad "276" smd rect
			(at -4.59994 116.45011 270)
			(size 1.8034 0.508)
			(layers "B.Cu" "B.Mask" "B.Paste")
			(net "GND")
		)
		(pad "277" smd rect
			(at -4.59994 117.299994 270)
			(size 1.8034 0.508)
			(layers "B.Cu" "B.Mask" "B.Paste")
			(net "M_M_DQS_DN<7>")
		)
		(pad "278" smd rect
			(at -4.59994 118.149878 270)
			(size 1.8034 0.508)
			(layers "B.Cu" "B.Mask" "B.Paste")
			(net "M_M_DQS_DP<7>")
		)
		(pad "279" smd rect
			(at -4.59994 119.000016 270)
			(size 1.8034 0.508)
			(layers "B.Cu" "B.Mask" "B.Paste")
			(net "GND")
		)
		(pad "280" smd rect
			(at -4.59994 119.8499 270)
			(size 1.8034 0.508)
			(layers "B.Cu" "B.Mask" "B.Paste")
			(net "M_M_DQ<63>")
		)
		(pad "281" smd rect
			(at -4.59994 120.700038 270)
			(size 1.8034 0.508)
			(layers "B.Cu" "B.Mask" "B.Paste")
			(net "GND")
		)
		(pad "282" smd rect
			(at -4.59994 121.549922 270)
			(size 1.8034 0.508)
			(layers "B.Cu" "B.Mask" "B.Paste")
			(net "M_M_DQ<59>")
		)
		(pad "283" smd rect
			(at -4.59994 122.40006 270)
			(size 1.8034 0.508)
			(layers "B.Cu" "B.Mask" "B.Paste")
			(net "GND")
		)
		(pad "284" smd rect
			(at -4.59994 123.249944 270)
			(size 1.8034 0.508)
			(layers "B.Cu" "B.Mask" "B.Paste")
			(net "PVPP_KLM")
		)
		(pad "285" smd rect
			(at -4.59994 124.100082 270)
			(size 1.8034 0.508)
			(layers "B.Cu" "B.Mask" "B.Paste")
			(net "SMB_DDR_KLM_VPP_SDA")
		)
		(pad "286" smd rect
			(at -4.59994 124.949966 270)
			(size 1.8034 0.508)
			(layers "B.Cu" "B.Mask" "B.Paste")
			(net "PVPP_KLM")
		)
		(pad "287" smd rect
			(at -4.59994 125.800104 270)
			(size 1.8034 0.508)
			(layers "B.Cu" "B.Mask" "B.Paste")
			(net "PVPP_KLM")
		)
		(pad "288" smd rect
			(at -4.59994 126.649988 270)
			(size 1.8034 0.508)
			(layers "B.Cu" "B.Mask" "B.Paste")
			(net "PVPP_KLM")
		)
	)
)
